(kicad_pcb
	(version 20260206)
	(generator "pcbnew")
	(generator_version "10.0")
	(general
		(thickness 1.6)
		(legacy_teardrops no)
	)
	(paper "A4")
	(title_block
		(title "03242023_DA0F0TMBIJ0_F0T_Motherboard_J_brd_V01_OCP.brd")
		(comment 1 "Grand Teton / footprints 4017-4020 of 6105")
	)
	(layers
		(0 "F.Cu" signal "TOP")
		(4 "In1.Cu" signal "GND")
		(6 "In2.Cu" signal "IN1")
		(8 "In3.Cu" signal "GND1")
		(10 "In4.Cu" signal "IN2")
		(12 "In5.Cu" signal "GND2")
		(14 "In6.Cu" signal "IN3")
		(16 "In7.Cu" signal "GND3")
		(18 "In8.Cu" signal "VCC")
		(20 "In9.Cu" signal "VCC1")
		(22 "In10.Cu" signal "GND4")
		(24 "In11.Cu" signal "IN4")
		(26 "In12.Cu" signal "GND5")
		(28 "In13.Cu" signal "IN5")
		(30 "In14.Cu" signal "GND6")
		(32 "In15.Cu" signal "IN6")
		(34 "In16.Cu" signal "GND7")
		(2 "B.Cu" signal "BOTTOM")
		(9 "F.Adhes" user "F.Adhesive")
		(11 "B.Adhes" user "B.Adhesive")
		(13 "F.Paste" user "Package Geometry/Pastemask Top")
		(15 "B.Paste" user "Package Geometry/Pastemask Bottom")
		(5 "F.SilkS" user "Ref Des/Silkscreen Top")
		(7 "B.SilkS" user "Ref Des/Silkscreen Bottom")
		(1 "F.Mask" user "Board Geometry/Soldermask Top")
		(3 "B.Mask" user "Board Geometry/Soldermask Bottom")
		(17 "Dwgs.User" user "User.Drawings")
		(19 "Cmts.User" user "User.Comments")
		(21 "Eco1.User" user "User.Eco1")
		(23 "Eco2.User" user "User.Eco2")
		(25 "Edge.Cuts" user "Board Geometry/Outline")
		(27 "Margin" user)
		(31 "F.CrtYd" user "Package Geometry/Place Bound Top")
		(29 "B.CrtYd" user "Package Geometry/Place Bound Bottom")
		(35 "F.Fab" user "Ref Des/Assembly Top")
		(33 "B.Fab" user "Ref Des/Assembly Bottom")
	)
	(footprint ""
		(layer "F.Cu")
		(at 361.258612 -333.716122)
		(property "Reference" "PU11_P0_3"
			(at -2.211832 -6.254496 0)
			(unlocked yes)
			(layer "F.SilkS")
			(effects
				(font
					(size 0.7874 0.5842)
					(thickness 0.1524)
				)
				(justify left)
			)
		)
		(property "Value" ""
			(at 0 0 0)
			(layer "F.Fab")
			(effects
				(font
					(size 1.27 1.27)
				)
			)
		)
		(duplicate_pad_numbers_are_jumpers no)
		(fp_line
			(start -2.500122 -2.999994)
			(end -2.24409 -2.999994)
			(stroke
				(width 0.1524)
				(type default)
			)
			(layer "F.SilkS")
		)
		(fp_line
			(start -2.500122 -2.529078)
			(end -2.500122 -2.999994)
			(stroke
				(width 0.1524)
				(type default)
			)
			(layer "F.SilkS")
		)
		(fp_line
			(start -2.500122 0.6604)
			(end -2.500122 0.229108)
			(stroke
				(width 0.1524)
				(type default)
			)
			(layer "F.SilkS")
		)
		(fp_line
			(start -2.500122 2.999994)
			(end -2.500122 2.339594)
			(stroke
				(width 0.1524)
				(type default)
			)
			(layer "F.SilkS")
		)
		(fp_line
			(start -2.2987 2.999994)
			(end -2.500122 2.999994)
			(stroke
				(width 0.1524)
				(type default)
			)
			(layer "F.SilkS")
		)
		(fp_line
			(start 2.31394 -2.999994)
			(end 2.500122 -2.999994)
			(stroke
				(width 0.1524)
				(type default)
			)
			(layer "F.SilkS")
		)
		(fp_line
			(start 2.500122 -2.999994)
			(end 2.500122 -2.44348)
			(stroke
				(width 0.1524)
				(type default)
			)
			(layer "F.SilkS")
		)
		(fp_line
			(start 2.500122 2.339594)
			(end 2.500122 2.999994)
			(stroke
				(width 0.1524)
				(type default)
			)
			(layer "F.SilkS")
		)
		(fp_line
			(start 2.500122 2.999994)
			(end 2.2987 2.999994)
			(stroke
				(width 0.1524)
				(type default)
			)
			(layer "F.SilkS")
		)
		(fp_poly
			(pts
				(xy -2.2479 -3.591306) (xy -2.7559 -2.575306) (xy -3.2639 -3.591306)
			)
			(stroke
				(width 0)
				(type default)
			)
			(fill yes)
			(layer "F.SilkS")
		)
		(fp_line
			(start -2.500122 -2.999994)
			(end 2.500122 -2.999994)
			(stroke
				(width 0.1)
				(type default)
			)
			(layer "F.Fab")
		)
		(fp_line
			(start -2.500122 2.999994)
			(end -2.500122 -2.999994)
			(stroke
				(width 0.1)
				(type default)
			)
			(layer "F.Fab")
		)
		(fp_line
			(start 2.500122 -2.999994)
			(end 2.500122 2.999994)
			(stroke
				(width 0.1)
				(type default)
			)
			(layer "F.Fab")
		)
		(fp_line
			(start 2.500122 2.999994)
			(end -2.500122 2.999994)
			(stroke
				(width 0.1)
				(type default)
			)
			(layer "F.Fab")
		)
		(fp_poly
			(pts
				(xy -4.218432 -2.783078) (xy -4.218432 -1.767078) (xy -3.202432 -2.275078)
			)
			(stroke
				(width 0)
				(type default)
			)
			(fill yes)
			(layer "F.Fab")
		)
		(pad "1" smd rect
			(at -2.400046 -2.275078 90)
			(size 0.2286 0.6096)
			(layers "F.Cu" "F.Mask" "F.Paste")
			(net "PVCCIN_CPU0_VOS3")
		)
		(pad "2" smd rect
			(at -2.400046 -1.82499 90)
			(size 0.2286 0.6096)
			(layers "F.Cu" "F.Mask" "F.Paste")
			(net "GND")
		)
		(pad "3" smd rect
			(at -2.400046 -1.374902 90)
			(size 0.2286 0.6096)
			(layers "F.Cu" "F.Mask" "F.Paste")
			(net "PVCCIN_CPU0_VDD3")
		)
		(pad "4" smd rect
			(at -2.400046 -0.925068 90)
			(size 0.2286 0.6096)
			(layers "F.Cu" "F.Mask" "F.Paste")
			(net "PVCCIN_CPU0_PVCC")
		)
		(pad "5" smd rect
			(at -2.400046 -0.47498 90)
			(size 0.2286 0.6096)
			(layers "F.Cu" "F.Mask" "F.Paste")
			(net "GND")
		)
		(pad "6" smd rect
			(at -2.400046 -0.024892 90)
			(size 0.2286 0.6096)
			(layers "F.Cu" "F.Mask" "F.Paste")
			(net "Net_8550")
		)
		(pad "7_9-20_24" smd circle
			(at 0 1.150112 90)
			(size 0 0)
			(layers "F.Cu" "F.Mask" "F.Paste")
			(net "GND")
		)
		(pad "10_19" smd rect
			(at 0 2.899918 90)
			(size 0.6096 4.318)
			(layers "F.Cu" "F.Mask" "F.Paste")
			(net "SW_PVCCIN_CPU0_SW3")
		)
		(pad "25_29" smd rect
			(at 1.549908 -1.279906 270)
			(size 2.0574 2.3114)
			(layers "F.Cu" "F.Mask" "F.Paste")
			(net "SW_P12V_PVCCIN_CPU0_FLT")
		)
		(pad "30" smd rect
			(at 2.05994 -2.899918)
			(size 0.2286 0.6096)
			(layers "F.Cu" "F.Mask" "F.Paste")
			(net "SW_P12V_PVCCIN_CPU0_FLT")
		)
		(pad "31" smd rect
			(at 1.610106 -2.899918)
			(size 0.2286 0.6096)
			(layers "F.Cu" "F.Mask" "F.Paste")
			(net "Net_8551")
		)
		(pad "32" smd rect
			(at 1.160018 -2.899918)
			(size 0.2286 0.6096)
			(layers "F.Cu" "F.Mask" "F.Paste")
			(net "SW_PVCCIN_CPU0_BOOTR3")
		)
		(pad "33" smd rect
			(at 0.70993 -2.899918)
			(size 0.2286 0.6096)
			(layers "F.Cu" "F.Mask" "F.Paste")
			(net "SW_PVCCIN_CPU0_BOOT3")
		)
		(pad "34" smd rect
			(at 0.260096 -2.899918)
			(size 0.2286 0.6096)
			(layers "F.Cu" "F.Mask" "F.Paste")
			(net "PVCCIN_CPU0_PWM3")
		)
		(pad "35" smd rect
			(at -0.189992 -2.899918)
			(size 0.2286 0.6096)
			(layers "F.Cu" "F.Mask" "F.Paste")
			(net "PVCCIN_CPU0_VDD3")
		)
		(pad "36" smd rect
			(at -0.64008 -2.899918)
			(size 0.2286 0.6096)
			(layers "F.Cu" "F.Mask" "F.Paste")
			(net "PVCCIN_CPU0_ATSEN")
		)
		(pad "37" smd rect
			(at -1.089914 -2.899918)
			(size 0.2286 0.6096)
			(layers "F.Cu" "F.Mask" "F.Paste")
			(net "PVCCIN_CPU0_LSET3")
		)
		(pad "38" smd rect
			(at -1.540002 -2.899918)
			(size 0.2286 0.6096)
			(layers "F.Cu" "F.Mask" "F.Paste")
			(net "PVCCIN_CPU0_IMON3")
		)
		(pad "39" smd rect
			(at -1.99009 -2.899918)
			(size 0.2286 0.6096)
			(layers "F.Cu" "F.Mask" "F.Paste")
			(net "PVCCIN_CPU0_VREF")
		)
		(pad "40" smd rect
			(at -0.87503 -1.27508)
			(size 1.7526 1.9558)
			(layers "F.Cu" "F.Mask" "F.Paste")
			(net "GND")
		)
		(pad "41" smd rect
			(at -1.525016 0.249936 270)
			(size 0.3048 0.4572)
			(layers "F.Cu" "F.Mask" "F.Paste")
			(net "Net_8549")
		)
		(zone
			(layer "F.Cu")
			(hatch none 0.5)
			(connect_pads
				(clearance 0)
			)
			(min_thickness 0.25)
			(keepout
				(tracks not_allowed)
				(vias allowed)
				(pads allowed)
				(copperpour not_allowed)
				(footprints allowed)
			)
			(placement
				(enabled no)
				(sheetname "")
			)
			(fill
				(thermal_gap 0.5)
				(thermal_bridge_width 0.5)
				(island_removal_mode 0)
			)
			(polygon
				(pts
					(xy 358.75849 -330.716128) (xy 358.75849 -331.465428) (xy 363.758734 -331.465428) (xy 363.758734 -330.716128)
					(xy 363.468412 -330.716128) (xy 363.468412 -331.171804) (xy 359.048812 -331.171804) (xy 359.048812 -330.716128)
				)
			)
		)
		(zone
			(layer "F.Cu")
			(hatch none 0.5)
			(connect_pads
				(clearance 0)
			)
			(min_thickness 0.25)
			(keepout
				(tracks not_allowed)
				(vias allowed)
				(pads allowed)
				(copperpour not_allowed)
				(footprints allowed)
			)
			(placement
				(enabled no)
				(sheetname "")
			)
			(fill
				(thermal_gap 0.5)
				(thermal_bridge_width 0.5)
				(island_removal_mode 0)
			)
			(polygon
				(pts
					(xy 359.214166 -334.028288) (xy 359.456482 -334.028288) (xy 359.456482 -333.962502) (xy 360.09072 -333.962502)
					(xy 360.09072 -333.647288) (xy 360.30789 -333.647288) (xy 360.30789 -332.966822) (xy 358.75849 -332.966822)
					(xy 358.75849 -333.423514) (xy 359.454196 -333.423514) (xy 359.454196 -333.262986) (xy 360.012996 -333.262986)
					(xy 360.012996 -333.669386) (xy 359.454196 -333.669386) (xy 359.454196 -333.448914) (xy 358.75849 -333.448914)
					(xy 358.75849 -333.575914) (xy 359.214166 -333.575914)
				)
			)
		)
	)
	(footprint ""
		(layer "F.Cu")
		(at 193.38036 -115.534948 180)
		(property "Reference" "R1812"
			(at 0 0 180)
			(layer "F.SilkS")
			(hide yes)
			(effects
				(font
					(size 1.27 1.27)
				)
			)
		)
		(property "Value" ""
			(at 0 0 180)
			(layer "F.Fab")
			(effects
				(font
					(size 1.27 1.27)
				)
			)
		)
		(duplicate_pad_numbers_are_jumpers no)
		(fp_line
			(start 0.7874 0.4064)
			(end -0.7874 0.4064)
			(stroke
				(width 0.1524)
				(type default)
			)
			(layer "F.SilkS")
		)
		(fp_line
			(start 0.7874 -0.4064)
			(end 0.7874 0.4064)
			(stroke
				(width 0.1524)
				(type default)
			)
			(layer "F.SilkS")
		)
		(fp_line
			(start -0.7874 0.4064)
			(end -0.7874 -0.4064)
			(stroke
				(width 0.1524)
				(type default)
			)
			(layer "F.SilkS")
		)
		(fp_line
			(start -0.7874 -0.4064)
			(end 0.7874 -0.4064)
			(stroke
				(width 0.1524)
				(type default)
			)
			(layer "F.SilkS")
		)
		(fp_line
			(start 0.67945 0.3048)
			(end 0.120396 0.3048)
			(stroke
				(width 0.1)
				(type default)
			)
			(layer "F.Fab")
		)
		(fp_line
			(start 0.67945 -0.3048)
			(end 0.67945 0.3048)
			(stroke
				(width 0.1)
				(type default)
			)
			(layer "F.Fab")
		)
		(fp_line
			(start 0.12065 -0.2794)
			(end 0.12065 -0.3048)
			(stroke
				(width 0.1)
				(type default)
			)
			(layer "F.Fab")
		)
		(fp_line
			(start 0.12065 -0.3048)
			(end 0.67945 -0.3048)
			(stroke
				(width 0.1)
				(type default)
			)
			(layer "F.Fab")
		)
		(fp_line
			(start 0.120396 0.3048)
			(end 0.120396 0.2794)
			(stroke
				(width 0.1)
				(type default)
			)
			(layer "F.Fab")
		)
		(fp_line
			(start 0.120396 0.2794)
			(end -0.12065 0.2794)
			(stroke
				(width 0.1)
				(type default)
			)
			(layer "F.Fab")
		)
		(fp_line
			(start -0.12065 0.3048)
			(end -0.67945 0.3048)
			(stroke
				(width 0.1)
				(type default)
			)
			(layer "F.Fab")
		)
		(fp_line
			(start -0.12065 0.2794)
			(end -0.12065 0.3048)
			(stroke
				(width 0.1)
				(type default)
			)
			(layer "F.Fab")
		)
		(fp_line
			(start -0.12065 -0.2794)
			(end 0.12065 -0.2794)
			(stroke
				(width 0.1)
				(type default)
			)
			(layer "F.Fab")
		)
		(fp_line
			(start -0.12065 -0.305054)
			(end -0.12065 -0.2794)
			(stroke
				(width 0.1)
				(type default)
			)
			(layer "F.Fab")
		)
		(fp_line
			(start -0.67945 0.3048)
			(end -0.67945 -0.305054)
			(stroke
				(width 0.1)
				(type default)
			)
			(layer "F.Fab")
		)
		(fp_line
			(start -0.67945 -0.305054)
			(end -0.12065 -0.305054)
			(stroke
				(width 0.1)
				(type default)
			)
			(layer "F.Fab")
		)
		(pad "1" smd circle
			(at -0.40005 0 180)
			(size 0 0)
			(layers "F.Cu" "F.Mask" "F.Paste")
			(net "IRQ_SGPIO_INTR_N")
		)
		(pad "2" smd circle
			(at 0.40005 0 180)
			(size 0 0)
			(layers "F.Cu" "F.Mask" "F.Paste")
			(net "IRQ_SGPIO_INTR_N_R")
		)
	)
	(footprint ""
		(layer "F.Cu")
		(at 22.809454 -111.383826)
		(property "Reference" "R3672"
			(at 0 0 0)
			(layer "F.SilkS")
			(hide yes)
			(effects
				(font
					(size 1.27 1.27)
				)
			)
		)
		(property "Value" ""
			(at 0 0 0)
			(layer "F.Fab")
			(effects
				(font
					(size 1.27 1.27)
				)
			)
		)
		(duplicate_pad_numbers_are_jumpers no)
		(fp_line
			(start -0.7874 -0.4064)
			(end 0.7874 -0.4064)
			(stroke
				(width 0.1524)
				(type default)
			)
			(layer "F.SilkS")
		)
		(fp_line
			(start -0.7874 0.4064)
			(end -0.7874 -0.4064)
			(stroke
				(width 0.1524)
				(type default)
			)
			(layer "F.SilkS")
		)
		(fp_line
			(start 0.7874 -0.4064)
			(end 0.7874 0.4064)
			(stroke
				(width 0.1524)
				(type default)
			)
			(layer "F.SilkS")
		)
		(fp_line
			(start 0.7874 0.4064)
			(end -0.7874 0.4064)
			(stroke
				(width 0.1524)
				(type default)
			)
			(layer "F.SilkS")
		)
		(fp_line
			(start -0.67945 -0.305054)
			(end -0.12065 -0.305054)
			(stroke
				(width 0.1)
				(type default)
			)
			(layer "F.Fab")
		)
		(fp_line
			(start -0.67945 0.3048)
			(end -0.67945 -0.305054)
			(stroke
				(width 0.1)
				(type default)
			)
			(layer "F.Fab")
		)
		(fp_line
			(start -0.12065 -0.305054)
			(end -0.12065 -0.2794)
			(stroke
				(width 0.1)
				(type default)
			)
			(layer "F.Fab")
		)
		(fp_line
			(start -0.12065 -0.2794)
			(end 0.12065 -0.2794)
			(stroke
				(width 0.1)
				(type default)
			)
			(layer "F.Fab")
		)
		(fp_line
			(start -0.12065 0.2794)
			(end -0.12065 0.3048)
			(stroke
				(width 0.1)
				(type default)
			)
			(layer "F.Fab")
		)
		(fp_line
			(start -0.12065 0.3048)
			(end -0.67945 0.3048)
			(stroke
				(width 0.1)
				(type default)
			)
			(layer "F.Fab")
		)
		(fp_line
			(start 0.120396 0.2794)
			(end -0.12065 0.2794)
			(stroke
				(width 0.1)
				(type default)
			)
			(layer "F.Fab")
		)
		(fp_line
			(start 0.120396 0.3048)
			(end 0.120396 0.2794)
			(stroke
				(width 0.1)
				(type default)
			)
			(layer "F.Fab")
		)
		(fp_line
			(start 0.12065 -0.3048)
			(end 0.67945 -0.3048)
			(stroke
				(width 0.1)
				(type default)
			)
			(layer "F.Fab")
		)
		(fp_line
			(start 0.12065 -0.2794)
			(end 0.12065 -0.3048)
			(stroke
				(width 0.1)
				(type default)
			)
			(layer "F.Fab")
		)
		(fp_line
			(start 0.67945 -0.3048)
			(end 0.67945 0.3048)
			(stroke
				(width 0.1)
				(type default)
			)
			(layer "F.Fab")
		)
		(fp_line
			(start 0.67945 0.3048)
			(end 0.120396 0.3048)
			(stroke
				(width 0.1)
				(type default)
			)
			(layer "F.Fab")
		)
		(pad "1" smd circle
			(at -0.40005 0)
			(size 0 0)
			(layers "F.Cu" "F.Mask" "F.Paste")
			(net "SMB_VR_3V3AUX_SCL_R1")
		)
		(pad "2" smd circle
			(at 0.40005 0)
			(size 0 0)
			(layers "F.Cu" "F.Mask" "F.Paste")
			(net "SMB_SEN_TIC_3V3AUX_SCL")
		)
	)
	(footprint ""
		(layer "F.Cu")
		(at 371.204998 -338.17814 -90)
		(property "Reference" "PC278"
			(at 0 0 270)
			(layer "F.SilkS")
			(hide yes)
			(effects
				(font
					(size 1.27 1.27)
				)
			)
		)
		(property "Value" ""
			(at 0 0 270)
			(layer "F.Fab")
			(effects
				(font
					(size 1.27 1.27)
				)
			)
		)
		(duplicate_pad_numbers_are_jumpers no)
		(fp_line
			(start -0.7874 0.4064)
			(end -0.7874 -0.4064)
			(stroke
				(width 0.1524)
				(type default)
			)
			(layer "F.SilkS")
		)
		(fp_line
			(start 0.7874 0.4064)
			(end -0.7874 0.4064)
			(stroke
				(width 0.1524)
				(type default)
			)
			(layer "F.SilkS")
		)
		(fp_line
			(start -0.7874 -0.4064)
			(end 0.7874 -0.4064)
			(stroke
				(width 0.1524)
				(type default)
			)
			(layer "F.SilkS")
		)
		(fp_line
			(start 0.7874 -0.4064)
			(end 0.7874 0.4064)
			(stroke
				(width 0.1524)
				(type default)
			)
			(layer "F.SilkS")
		)
		(fp_line
			(start -0.67945 0.3048)
			(end -0.67945 -0.305054)
			(stroke
				(width 0.1)
				(type default)
			)
			(layer "F.Fab")
		)
		(fp_line
			(start -0.12065 0.3048)
			(end -0.67945 0.3048)
			(stroke
				(width 0.1)
				(type default)
			)
			(layer "F.Fab")
		)
		(fp_line
			(start 0.120396 0.3048)
			(end 0.120396 0.2794)
			(stroke
				(width 0.1)
				(type default)
			)
			(layer "F.Fab")
		)
		(fp_line
			(start 0.67945 0.3048)
			(end 0.120396 0.3048)
			(stroke
				(width 0.1)
				(type default)
			)
			(layer "F.Fab")
		)
		(fp_line
			(start -0.12065 0.2794)
			(end -0.12065 0.3048)
			(stroke
				(width 0.1)
				(type default)
			)
			(layer "F.Fab")
		)
		(fp_line
			(start 0.120396 0.2794)
			(end -0.12065 0.2794)
			(stroke
				(width 0.1)
				(type default)
			)
			(layer "F.Fab")
		)
		(fp_line
			(start -0.12065 -0.2794)
			(end 0.12065 -0.2794)
			(stroke
				(width 0.1)
				(type default)
			)
			(layer "F.Fab")
		)
		(fp_line
			(start 0.12065 -0.2794)
			(end 0.12065 -0.3048)
			(stroke
				(width 0.1)
				(type default)
			)
			(layer "F.Fab")
		)
		(fp_line
			(start 0.12065 -0.3048)
			(end 0.67945 -0.3048)
			(stroke
				(width 0.1)
				(type default)
			)
			(layer "F.Fab")
		)
		(fp_line
			(start 0.67945 -0.3048)
			(end 0.67945 0.3048)
			(stroke
				(width 0.1)
				(type default)
			)
			(layer "F.Fab")
		)
		(fp_line
			(start -0.67945 -0.305054)
			(end -0.12065 -0.305054)
			(stroke
				(width 0.1)
				(type default)
			)
			(layer "F.Fab")
		)
		(fp_line
			(start -0.12065 -0.305054)
			(end -0.12065 -0.2794)
			(stroke
				(width 0.1)
				(type default)
			)
			(layer "F.Fab")
		)
		(pad "1" smd circle
			(at -0.40005 0 270)
			(size 0 0)
			(layers "F.Cu" "F.Mask" "F.Paste")
			(net "SW_PVCCIN_CPU0_BOOT4_R")
		)
		(pad "2" smd circle
			(at 0.40005 0 270)
			(size 0 0)
			(layers "F.Cu" "F.Mask" "F.Paste")
			(net "SW_PVCCIN_CPU0_BOOTR4")
		)
	)
)
